(kicad_pcb
	(version 20241229)
	(generator "pcbnew")
	(generator_version "9.0")
	(general
		(thickness 1.294)
		(legacy_teardrops no)
	)
	(paper "A3")
	(title_block
		(title "Kintex 410T devboard")
		(date "2024-04-03")
		(rev "1.1.2")
		(comment 9 "footprints 308-313 of 975")
	)
	(layers
		(0 "F.Cu" mixed)
		(4 "In1.Cu" power)
		(6 "In2.Cu" power)
		(8 "In3.Cu" mixed)
		(10 "In4.Cu" power)
		(12 "In5.Cu" mixed)
		(14 "In6.Cu" power)
		(16 "In7.Cu" mixed)
		(18 "In8.Cu" power)
		(2 "B.Cu" mixed)
		(9 "F.Adhes" user "F.Adhesive")
		(11 "B.Adhes" user "B.Adhesive")
		(13 "F.Paste" user)
		(15 "B.Paste" user)
		(5 "F.SilkS" user "F.Silkscreen")
		(7 "B.SilkS" user "B.Silkscreen")
		(1 "F.Mask" user)
		(3 "B.Mask" user)
		(17 "Dwgs.User" user "User.Drawings")
		(19 "Cmts.User" user "User.Comments")
		(21 "Eco1.User" user "User.Eco1")
		(23 "Eco2.User" user "User.Eco2")
		(25 "Edge.Cuts" user)
		(27 "Margin" user)
		(31 "F.CrtYd" user "F.Courtyard")
		(29 "B.CrtYd" user "B.Courtyard")
		(35 "F.Fab" user)
		(33 "B.Fab" user)
	)
	(footprint "antmicro-footprints:Vishay_PowerPAK_1212-8_Single"
		(layer "F.Cu")
		(at 231.235 157.2)
		(descr "PowerPAK 1212-8 Single")
		(tags "Vishay PowerPAK 1212-8 Single")
		(property "Reference" "Q3"
			(at -2.1 -1.9 0)
			(layer "F.SilkS")
			(effects
				(font
					(size 0.7 0.7)
					(thickness 0.15)
				)
				(justify left bottom)
			)
		)
		(property "Value" "SI7613DN-T1-GE3"
			(at -8 2.7 0)
			(layer "F.Fab")
			(effects
				(font
					(size 0.7 0.7)
					(thickness 0.15)
				)
				(justify left bottom)
			)
		)
		(property "Description" "Power MOSFET, P Channel, 20 V, 35 A, 0.0072 ohm, PowerPAK 1212, Surface Mount"
			(at 0 0 0)
			(layer "F.Fab")
			(hide yes)
			(effects
				(font
					(size 1.27 1.27)
					(thickness 0.15)
				)
			)
		)
		(property "Author" "Antmicro"
			(at 0 0 0)
			(layer "F.Fab")
			(hide yes)
			(effects
				(font
					(size 1 1)
					(thickness 0.15)
				)
			)
		)
		(property "License" "Apache-2.0"
			(at 0 0 0)
			(layer "F.Fab")
			(hide yes)
			(effects
				(font
					(size 1 1)
					(thickness 0.15)
				)
			)
		)
		(property "MPN" "SI7613DN-T1-GE3"
			(at 0 0 0)
			(layer "F.Fab")
			(hide yes)
			(effects
				(font
					(size 1 1)
					(thickness 0.15)
				)
			)
		)
		(property "Manufacturer" "Vishay"
			(at 0 0 0)
			(layer "F.Fab")
			(hide yes)
			(effects
				(font
					(size 1 1)
					(thickness 0.15)
				)
			)
		)
		(sheetname "Power supply")
		(sheetfile "power-supply.kicad_sch")
		(attr smd)
		(fp_line
			(start -1.651 -1.651)
			(end -1.651 -1.317)
			(stroke
				(width 0.15)
				(type solid)
			)
			(layer "F.SilkS")
		)
		(fp_line
			(start -1.651 -1.651)
			(end 1.648 -1.651)
			(stroke
				(width 0.15)
				(type solid)
			)
			(layer "F.SilkS")
		)
		(fp_line
			(start -1.635 1.3)
			(end -1.635 1.634)
			(stroke
				(width 0.15)
				(type solid)
			)
			(layer "F.SilkS")
		)
		(fp_line
			(start -1.635 1.634)
			(end 1.634 1.634)
			(stroke
				(width 0.15)
				(type solid)
			)
			(layer "F.SilkS")
		)
		(fp_line
			(start 1.634 1.3)
			(end 1.634 1.634)
			(stroke
				(width 0.15)
				(type solid)
			)
			(layer "F.SilkS")
		)
		(fp_line
			(start 1.648 -1.651)
			(end 1.648 -1.317)
			(stroke
				(width 0.15)
				(type solid)
			)
			(layer "F.SilkS")
		)
		(fp_circle
			(center -1.9 -1.4)
			(end -1.85 -1.4)
			(stroke
				(width 0.15)
				(type solid)
			)
			(fill yes)
			(layer "F.SilkS")
		)
		(fp_rect
			(start -2 -1.8)
			(end 2 1.798)
			(stroke
				(width 0.05)
				(type solid)
			)
			(fill no)
			(layer "F.CrtYd")
		)
		(fp_line
			(start -1.6425 -1.4175)
			(end -1.4175 -1.6425)
			(stroke
				(width 0.15)
				(type solid)
			)
			(layer "F.Fab")
		)
		(fp_rect
			(start -1.651 -1.651)
			(end 1.648 1.648)
			(stroke
				(width 0.15)
				(type solid)
			)
			(fill no)
			(layer "F.Fab")
		)
		(pad "1" smd rect
			(at -1.436 -0.99)
			(size 0.99 0.405)
			(layers "F.Cu" "F.Mask" "F.Paste")
			(net 5 "/Power supply/PD_VBUS")
			(pinfunction "S")
			(pintype "passive")
		)
		(pad "2" smd rect
			(at -1.436 -0.332)
			(size 0.99 0.405)
			(layers "F.Cu" "F.Mask" "F.Paste")
			(net 5 "/Power supply/PD_VBUS")
			(pinfunction "S")
			(pintype "passive")
		)
		(pad "3" smd rect
			(at -1.436 0.33)
			(size 0.99 0.405)
			(layers "F.Cu" "F.Mask" "F.Paste")
			(net 5 "/Power supply/PD_VBUS")
			(pinfunction "S")
			(pintype "passive")
		)
		(pad "4" smd rect
			(at -1.436 0.988)
			(size 0.99 0.405)
			(layers "F.Cu" "F.Mask" "F.Paste")
			(net 872 "/Power supply/SINK_EN")
			(pinfunction "G")
			(pintype "passive")
		)
		(pad "5" smd custom
			(at 0.557 0)
			(size 1.725 2.235)
			(layers "F.Cu" "F.Mask" "F.Paste")
			(net 704 "/Power supply/USB_DBG_PD.VBUS")
			(pinfunction "D")
			(pintype "passive")
			(zone_connect 2)
			(options
				(clearance outline)
				(anchor rect)
			)
			(primitives
				(gr_poly
					(pts
						(xy 0.8625 0.1275) (xy 0.8625 -0.1275) (xy 1.3725 -0.1275) (xy 1.3725 -0.5325) (xy 0.8625 -0.5325)
						(xy 0.8625 -0.7875) (xy 1.3725 -0.7875) (xy 1.3725 -1.195) (xy 0.6125 -1.195) (xy 0.6125 1.195)
						(xy 1.3725 1.195) (xy 1.3725 0.7875) (xy 0.8625 0.7875) (xy 0.8625 0.5325) (xy 1.3725 0.5325)
						(xy 1.3725 0.1275)
					)
					(width 0)
					(fill yes)
				)
			)
		)
	)
	(footprint "antmicro-footprints:NetTie-2_SMD_Pad0.127mm"
		(layer "F.Cu")
		(at 160.773 145.3)
		(descr "Net tie, 2 pin, 0.127mm  SMD pads")
		(tags "net tie")
		(property "Reference" "NT2"
			(at -0.128 -1.345 0)
			(layer "F.SilkS")
			(hide yes)
			(effects
				(font
					(size 0.7 0.7)
					(thickness 0.15)
				)
				(justify left bottom)
			)
		)
		(property "Value" "Net-Tie_2"
			(at 0 1.199 0)
			(layer "F.Fab")
			(effects
				(font
					(size 0.7 0.7)
					(thickness 0.15)
				)
				(justify left bottom)
			)
		)
		(property "Description" "Net tie, 2 pins"
			(at 0 0 0)
			(layer "F.Fab")
			(hide yes)
			(effects
				(font
					(size 1.27 1.27)
					(thickness 0.15)
				)
			)
		)
		(property "Author" "Antmicro"
			(at 0 0 0)
			(layer "F.Fab")
			(hide yes)
			(effects
				(font
					(size 1 1)
					(thickness 0.15)
				)
			)
		)
		(property "License" "Apache-2.0"
			(at 0 0 0)
			(layer "F.Fab")
			(hide yes)
			(effects
				(font
					(size 1 1)
					(thickness 0.15)
				)
			)
		)
		(property "MPN" ""
			(at 0 0 0)
			(layer "F.Fab")
			(hide yes)
			(effects
				(font
					(size 1 1)
					(thickness 0.15)
				)
			)
		)
		(property "Manufacturer" ""
			(at 0 0 0)
			(layer "F.Fab")
			(hide yes)
			(effects
				(font
					(size 1 1)
					(thickness 0.15)
				)
			)
		)
		(sheetname "DC-DC Converters")
		(sheetfile "dc-dc.kicad_sch")
		(attr exclude_from_pos_files)
		(net_tie_pad_groups "1, 2")
		(fp_poly
			(pts
				(xy -0.0635 -0.0635) (xy 0.0625 -0.0635) (xy 0.0625 0.0635) (xy -0.0635 0.0635)
			)
			(stroke
				(width 0)
				(type solid)
			)
			(fill yes)
			(layer "F.Cu")
		)
		(pad "1" smd roundrect
			(at -0.127 0 180)
			(size 0.127 0.127)
			(layers "F.Cu")
			(roundrect_rratio 0.5)
			(chamfer_ratio 0)
			(chamfer top_left bottom_left)
			(net 1 "GND")
			(pinfunction "1")
			(pintype "passive")
		)
		(pad "2" smd roundrect
			(at 0.126 0)
			(size 0.127 0.127)
			(layers "F.Cu")
			(roundrect_rratio 0.5)
			(chamfer_ratio 0)
			(chamfer top_left bottom_left)
			(net 870 "VREFN")
			(pinfunction "2")
			(pintype "passive")
		)
	)
	(footprint "antmicro-footprints:SW_KMR211NGLFS_SMD"
		(layer "F.Cu")
		(at 266.8 79.4 180)
		(property "Reference" "S2"
			(at 0.7 -2.6 180)
			(layer "F.SilkS")
			(effects
				(font
					(size 0.7 0.7)
					(thickness 0.15)
				)
				(justify left bottom)
			)
		)
		(property "Value" "SW_KMR211NGLFS_SMD"
			(at -3 3 180)
			(layer "F.Fab")
			(effects
				(font
					(size 0.7 0.7)
					(thickness 0.15)
				)
				(justify left bottom)
			)
		)
		(property "Description" "Tactile Switch, KMR 2 Series, Top Actuated, Surface Mount, Oval Button, 120 gf, 50mA at 32VDC"
			(at 0 0 180)
			(layer "F.Fab")
			(hide yes)
			(effects
				(font
					(size 1.27 1.27)
					(thickness 0.15)
				)
			)
		)
		(property "Author" "Antmicro"
			(at 533.6 158.8 0)
			(layer "F.Fab")
			(hide yes)
			(effects
				(font
					(size 1 1)
					(thickness 0.15)
				)
			)
		)
		(property "License" "Apache-2.0"
			(at 533.6 158.8 0)
			(layer "F.Fab")
			(hide yes)
			(effects
				(font
					(size 1 1)
					(thickness 0.15)
				)
			)
		)
		(property "MPN" "KMR211NGLFS"
			(at 533.6 158.8 0)
			(layer "F.Fab")
			(hide yes)
			(effects
				(font
					(size 1 1)
					(thickness 0.15)
				)
			)
		)
		(property "Manufacturer" "C&K"
			(at 533.6 158.8 0)
			(layer "F.Fab")
			(hide yes)
			(effects
				(font
					(size 1 1)
					(thickness 0.15)
				)
			)
		)
		(sheetname "User GPIO + LED + button + DIP switch")
		(sheetfile "user-gpio.kicad_sch")
		(attr smd)
		(fp_line
			(start 2.101 1.601)
			(end 2.101 1.48)
			(stroke
				(width 0.15)
				(type solid)
			)
			(layer "F.SilkS")
		)
		(fp_line
			(start 2.101 1.601)
			(end -2.1 1.601)
			(stroke
				(width 0.15)
				(type solid)
			)
			(layer "F.SilkS")
		)
		(fp_line
			(start 2.101 -1.58)
			(end 2.101 -1.459)
			(stroke
				(width 0.15)
				(type solid)
			)
			(layer "F.SilkS")
		)
		(fp_line
			(start 2.101 -1.6)
			(end -2.1 -1.6)
			(stroke
				(width 0.15)
				(type solid)
			)
			(layer "F.SilkS")
		)
		(fp_line
			(start -2.1 1.601)
			(end -2.1 1.48)
			(stroke
				(width 0.15)
				(type solid)
			)
			(layer "F.SilkS")
		)
		(fp_line
			(start -2.1 -1.6)
			(end -2.1 -1.499)
			(stroke
				(width 0.15)
				(type solid)
			)
			(layer "F.SilkS")
		)
		(fp_rect
			(start 2.751 1.75)
			(end -2.748 -1.749)
			(stroke
				(width 0.05)
				(type solid)
			)
			(fill no)
			(layer "F.CrtYd")
		)
		(fp_line
			(start 2.101 1.601)
			(end 2.101 -1.6)
			(stroke
				(width 0.15)
				(type solid)
			)
			(layer "F.Fab")
		)
		(fp_line
			(start 2.101 -1.6)
			(end -2.1 -1.6)
			(stroke
				(width 0.15)
				(type solid)
			)
			(layer "F.Fab")
		)
		(fp_line
			(start 0.25 0.802)
			(end -0.248 0.802)
			(stroke
				(width 0.15)
				(type solid)
			)
			(layer "F.Fab")
		)
		(fp_line
			(start -0.248 -0.8)
			(end 0.25 -0.8)
			(stroke
				(width 0.15)
				(type solid)
			)
			(layer "F.Fab")
		)
		(fp_line
			(start -2.1 1.601)
			(end 2.101 1.601)
			(stroke
				(width 0.15)
				(type solid)
			)
			(layer "F.Fab")
		)
		(fp_line
			(start -2.1 -1.6)
			(end -2.1 1.601)
			(stroke
				(width 0.15)
				(type solid)
			)
			(layer "F.Fab")
		)
		(fp_arc
			(start 0.25 -0.8)
			(mid 1.051001 0.001)
			(end 0.25 0.802)
			(stroke
				(width 0.15)
				(type solid)
			)
			(layer "F.Fab")
		)
		(fp_arc
			(start -0.248 0.802)
			(mid -1.050001 0.001)
			(end -0.248 -0.8)
			(stroke
				(width 0.15)
				(type solid)
			)
			(layer "F.Fab")
		)
		(pad "1" smd rect
			(at -2.048 -0.8)
			(size 0.9 1)
			(layers "F.Cu" "F.Mask" "F.Paste")
			(net 1228 "/USER_IO.BUTTON0")
			(pinfunction "1")
			(pintype "passive")
		)
		(pad "2" smd rect
			(at 2.05 -0.8)
			(size 0.9 1)
			(layers "F.Cu" "F.Mask" "F.Paste")
			(net 1228 "/USER_IO.BUTTON0")
			(pinfunction "2")
			(pintype "passive")
		)
		(pad "3" smd rect
			(at -2.048 0.802)
			(size 0.9 1)
			(layers "F.Cu" "F.Mask" "F.Paste")
			(net 1 "GND")
			(pinfunction "3")
			(pintype "passive")
		)
		(pad "4" smd rect
			(at 2.05 0.802)
			(size 0.9 1)
			(layers "F.Cu" "F.Mask" "F.Paste")
			(net 1 "GND")
			(pinfunction "4")
			(pintype "passive")
		)
	)
	(footprint "antmicro-footprints:R_0402_1005Metric"
		(layer "F.Cu")
		(at 259.6 126.5 180)
		(descr "Resistor SMD 0402")
		(tags "resistor SMD 0402")
		(property "Reference" "R173"
			(at 1.05 5.7 180)
			(layer "F.SilkS")
			(effects
				(font
					(size 0.7 0.7)
					(thickness 0.15)
				)
				(justify left bottom)
			)
		)
		(property "Value" "R_33R_0402"
			(at 0 1.4 180)
			(layer "F.Fab")
			(effects
				(font
					(size 0.7 0.7)
					(thickness 0.15)
				)
				(justify left bottom)
			)
		)
		(property "Description" "SMD Chip Resistor, 33 ohm, ± 1%, 62.5 mW, 0402 [1005 Metric], Thick Film, General Purpose"
			(at 0 0 180)
			(layer "F.Fab")
			(hide yes)
			(effects
				(font
					(size 1.27 1.27)
					(thickness 0.15)
				)
			)
		)
		(property "Author" "Antmicro"
			(at 519.2 253 0)
			(layer "F.Fab")
			(hide yes)
			(effects
				(font
					(size 1 1)
					(thickness 0.15)
				)
			)
		)
		(property "License" "Apache-2.0"
			(at 519.2 253 0)
			(layer "F.Fab")
			(hide yes)
			(effects
				(font
					(size 1 1)
					(thickness 0.15)
				)
			)
		)
		(property "MPN" "CR0402-FX-33R0GLF"
			(at 519.2 253 0)
			(layer "F.Fab")
			(hide yes)
			(effects
				(font
					(size 1 1)
					(thickness 0.15)
				)
			)
		)
		(property "Manufacturer" "Bourns"
			(at 519.2 253 0)
			(layer "F.Fab")
			(hide yes)
			(effects
				(font
					(size 1 1)
					(thickness 0.15)
				)
			)
		)
		(property "Tolerance" "1%"
			(at 519.2 253 0)
			(layer "F.Fab")
			(hide yes)
			(effects
				(font
					(size 1 1)
					(thickness 0.15)
				)
			)
		)
		(property "Val" "33R"
			(at 519.2 253 0)
			(layer "F.Fab")
			(hide yes)
			(effects
				(font
					(size 1 1)
					(thickness 0.15)
				)
			)
		)
		(sheetname "USB PHY")
		(sheetfile "usb-phy.kicad_sch")
		(attr smd)
		(fp_rect
			(start -0.925 -0.47)
			(end 0.925 0.47)
			(stroke
				(width 0.05)
				(type default)
			)
			(fill no)
			(layer "F.CrtYd")
		)
		(fp_rect
			(start -0.5 -0.25)
			(end 0.5 0.25)
			(stroke
				(width 0.15)
				(type solid)
			)
			(fill no)
			(layer "F.Fab")
		)
		(pad "1" smd roundrect
			(at -0.48 0 180)
			(size 0.59 0.64)
			(layers "F.Cu" "F.Mask" "F.Paste")
			(roundrect_rratio 0.25)
			(net 843 "/USB PHY/USB_USR_CONN_D-")
			(pintype "passive")
		)
		(pad "2" smd roundrect
			(at 0.48 0 180)
			(size 0.59 0.64)
			(layers "F.Cu" "F.Mask" "F.Paste")
			(roundrect_rratio 0.25)
			(net 927 "/USB PHY/USB_USR_D-")
			(pintype "passive")
		)
	)
	(footprint "antmicro-footprints:C_0402_1005Metric"
		(layer "F.Cu")
		(at 233.8 145.4 -90)
		(descr "Capacitor SMD 0402")
		(tags "capacitor SMD 0402")
		(property "Reference" "C244"
			(at 1.4 -1.23 270)
			(layer "F.SilkS")
			(effects
				(font
					(size 0.7 0.7)
					(thickness 0.15)
				)
				(justify left bottom)
			)
		)
		(property "Value" "C_100n_0402"
			(at 0 1.169 270)
			(layer "F.Fab")
			(effects
				(font
					(size 0.7 0.7)
					(thickness 0.15)
				)
				(justify left bottom)
			)
		)
		(property "Description" "SMD Multilayer Ceramic Capacitor, 0.1 µF, 50 V, 0402 [1005 Metric], ± 10%, X5R, GRM Series"
			(at 0 0 270)
			(layer "F.Fab")
			(hide yes)
			(effects
				(font
					(size 1.27 1.27)
					(thickness 0.15)
				)
			)
		)
		(property "Author" "Antmicro"
			(at 88.4 379.2 0)
			(layer "F.Fab")
			(hide yes)
			(effects
				(font
					(size 1 1)
					(thickness 0.15)
				)
			)
		)
		(property "Dielectric" "X5R"
			(at 88.4 379.2 0)
			(layer "F.Fab")
			(hide yes)
			(effects
				(font
					(size 1 1)
					(thickness 0.15)
				)
			)
		)
		(property "License" "Apache-2.0"
			(at 88.4 379.2 0)
			(layer "F.Fab")
			(hide yes)
			(effects
				(font
					(size 1 1)
					(thickness 0.15)
				)
			)
		)
		(property "MPN" "GRM155R61H104KE14D"
			(at 88.4 379.2 0)
			(layer "F.Fab")
			(hide yes)
			(effects
				(font
					(size 1 1)
					(thickness 0.15)
				)
			)
		)
		(property "Manufacturer" "Murata"
			(at 88.4 379.2 0)
			(layer "F.Fab")
			(hide yes)
			(effects
				(font
					(size 1 1)
					(thickness 0.15)
				)
			)
		)
		(property "Val" "100n"
			(at 88.4 379.2 0)
			(layer "F.Fab")
			(hide yes)
			(effects
				(font
					(size 1 1)
					(thickness 0.15)
				)
			)
		)
		(property "Voltage" "50V"
			(at 88.4 379.2 0)
			(layer "F.Fab")
			(hide yes)
			(effects
				(font
					(size 1 1)
					(thickness 0.15)
				)
			)
		)
		(sheetname "USB PHY")
		(sheetfile "usb-phy.kicad_sch")
		(attr smd)
		(fp_rect
			(start -0.925 -0.47)
			(end 0.925 0.47)
			(stroke
				(width 0.05)
				(type default)
			)
			(fill no)
			(layer "F.CrtYd")
		)
		(fp_line
			(start -0.494 0.248)
			(end -0.494 -0.25)
			(stroke
				(width 0.15)
				(type solid)
			)
			(layer "F.Fab")
		)
		(fp_line
			(start 0.504 0.248)
			(end -0.494 0.248)
			(stroke
				(width 0.15)
				(type solid)
			)
			(layer "F.Fab")
		)
		(fp_line
			(start -0.494 -0.25)
			(end 0.504 -0.25)
			(stroke
				(width 0.15)
				(type solid)
			)
			(layer "F.Fab")
		)
		(fp_line
			(start 0.504 -0.25)
			(end 0.504 0.248)
			(stroke
				(width 0.15)
				(type solid)
			)
			(layer "F.Fab")
		)
		(pad "1" smd roundrect
			(at -0.48 0 270)
			(size 0.59 0.64)
			(layers "F.Cu" "F.Mask" "F.Paste")
			(roundrect_rratio 0.25)
			(net 1 "GND")
			(pintype "passive")
		)
		(pad "2" smd roundrect
			(at 0.48 0 270)
			(size 0.59 0.64)
			(layers "F.Cu" "F.Mask" "F.Paste")
			(roundrect_rratio 0.25)
			(net 24 "+3V3")
			(pintype "passive")
		)
	)
	(footprint "antmicro-footprints:C_0402_1005Metric"
		(layer "F.Cu")
		(at 245.6 141.6 90)
		(descr "Capacitor SMD 0402")
		(tags "capacitor SMD 0402")
		(property "Reference" "C233"
			(at -1.7 6.4 90)
			(layer "F.SilkS")
			(effects
				(font
					(size 0.7 0.7)
					(thickness 0.15)
				)
				(justify left bottom)
			)
		)
		(property "Value" "C_100n_0402"
			(at 0 1.169 90)
			(layer "F.Fab")
			(effects
				(font
					(size 0.7 0.7)
					(thickness 0.15)
				)
				(justify left bottom)
			)
		)
		(property "Description" "SMD Multilayer Ceramic Capacitor, 0.1 µF, 50 V, 0402 [1005 Metric], ± 10%, X5R, GRM Series"
			(at 0 0 90)
			(layer "F.Fab")
			(hide yes)
			(effects
				(font
					(size 1.27 1.27)
					(thickness 0.15)
				)
			)
		)
		(property "Author" "Antmicro"
			(at 387.2 -104 0)
			(layer "F.Fab")
			(hide yes)
			(effects
				(font
					(size 1 1)
					(thickness 0.15)
				)
			)
		)
		(property "Dielectric" "X5R"
			(at 387.2 -104 0)
			(layer "F.Fab")
			(hide yes)
			(effects
				(font
					(size 1 1)
					(thickness 0.15)
				)
			)
		)
		(property "License" "Apache-2.0"
			(at 387.2 -104 0)
			(layer "F.Fab")
			(hide yes)
			(effects
				(font
					(size 1 1)
					(thickness 0.15)
				)
			)
		)
		(property "MPN" "GRM155R61H104KE14D"
			(at 387.2 -104 0)
			(layer "F.Fab")
			(hide yes)
			(effects
				(font
					(size 1 1)
					(thickness 0.15)
				)
			)
		)
		(property "Manufacturer" "Murata"
			(at 387.2 -104 0)
			(layer "F.Fab")
			(hide yes)
			(effects
				(font
					(size 1 1)
					(thickness 0.15)
				)
			)
		)
		(property "Val" "100n"
			(at 387.2 -104 0)
			(layer "F.Fab")
			(hide yes)
			(effects
				(font
					(size 1 1)
					(thickness 0.15)
				)
			)
		)
		(property "Voltage" "50V"
			(at 387.2 -104 0)
			(layer "F.Fab")
			(hide yes)
			(effects
				(font
					(size 1 1)
					(thickness 0.15)
				)
			)
		)
		(sheetname "USB PHY")
		(sheetfile "usb-phy.kicad_sch")
		(attr smd)
		(fp_rect
			(start -0.925 -0.47)
			(end 0.925 0.47)
			(stroke
				(width 0.05)
				(type default)
			)
			(fill no)
			(layer "F.CrtYd")
		)
		(fp_line
			(start 0.504 -0.25)
			(end 0.504 0.248)
			(stroke
				(width 0.15)
				(type solid)
			)
			(layer "F.Fab")
		)
		(fp_line
			(start -0.494 -0.25)
			(end 0.504 -0.25)
			(stroke
				(width 0.15)
				(type solid)
			)
			(layer "F.Fab")
		)
		(fp_line
			(start 0.504 0.248)
			(end -0.494 0.248)
			(stroke
				(width 0.15)
				(type solid)
			)
			(layer "F.Fab")
		)
		(fp_line
			(start -0.494 0.248)
			(end -0.494 -0.25)
			(stroke
				(width 0.15)
				(type solid)
			)
			(layer "F.Fab")
		)
		(pad "1" smd roundrect
			(at -0.48 0 90)
			(size 0.59 0.64)
			(layers "F.Cu" "F.Mask" "F.Paste")
			(roundrect_rratio 0.25)
			(net 1 "GND")
			(pintype "passive")
		)
		(pad "2" smd roundrect
			(at 0.48 0 90)
			(size 0.59 0.64)
			(layers "F.Cu" "F.Mask" "F.Paste")
			(roundrect_rratio 0.25)
			(net 707 "/USB PHY/FTDI_3V3")
			(pintype "passive")
		)
	)
)
